(kicad_pcb
	(version 20221018)
	(generator pcbnew)
	(general
    (thickness 1.6)
  )
	(paper "A4")
	(title_block
    (title "NUC Computer Cluster Power Breakout HW")
    (date "2023-10-18")
    (rev "1.4.3")
    (company "Antmicro Ltd.")
		(comment 9 "footprints 35-40 of 234")
	)
	(layers
    (0 "F.Cu" mixed)
    (1 "In1.Cu" power)
    (2 "In2.Cu" mixed)
    (31 "B.Cu" power)
    (32 "B.Adhes" user "B.Adhesive")
    (33 "F.Adhes" user "F.Adhesive")
    (34 "B.Paste" user)
    (35 "F.Paste" user)
    (36 "B.SilkS" user "B.Silkscreen")
    (37 "F.SilkS" user "F.Silkscreen")
    (38 "B.Mask" user)
    (39 "F.Mask" user)
    (40 "Dwgs.User" user "User.Drawings")
    (41 "Cmts.User" user "User.Comments")
    (42 "Eco1.User" user "User.Eco1")
    (43 "Eco2.User" user "User.Eco2")
    (44 "Edge.Cuts" user)
    (45 "Margin" user)
    (46 "B.CrtYd" user "B.Courtyard")
    (47 "F.CrtYd" user "F.Courtyard")
    (48 "B.Fab" user)
    (49 "F.Fab" user)
  )
	(footprint "antmicro-footprints:R_0402_1005Metric" (layer "F.Cu")
    (at 178.75 85.8 -90)
    (descr "Resistor SMD 0402")
    (tags "resistor SMD 0402")
    (property "Author" "Antmicro")
    (property "License" "Apache-2.0")
    (property "MPN" "CR0402-FX-1002GLF")
    (property "Manufacturer" "Bourns")
    (property "Sheetfile" "power-switch.kicad_sch")
    (property "Sheetname" "Power switch 5")
    (property "Tolerance" "1%")
    (property "Val" "10k")
    (property "ki_description" "SMD Chip Resistor, 10 kohm, ± 1%, 62.5 mW, 0402 [1005 Metric], Thick Film, General Purpose")
    (property "ki_keywords" "0402, SMT, RESISTOR, PASSIVE")
    (attr smd)
    (fp_text reference "R24" (at -0.1 -0.85 90) (layer "F.SilkS")
        (effects (font (size 0.7 0.7) (thickness 0.15)))
    )
    (fp_text value "R_10k_0402" (at 0 1.17 90) (layer "F.Fab") hide
        (effects (font (size 1 1) (thickness 0.15)))
    )
    (fp_text user "License: Apache-2.0" (at -0.95 5.169 -90) (layer "F.Fab") hide
        (effects (font (size 0.7 0.7) (thickness 0.15)) (justify left bottom))
    )
    (fp_text user "${REFERENCE}" (at 0 0 90) (layer "F.Fab")
        (effects (font (size 0.7 0.7) (thickness 0.15)))
    )
    (fp_text user "Author: Antmicro" (at -0.95 4.169 -90) (layer "F.Fab") hide
        (effects (font (size 0.7 0.7) (thickness 0.15)) (justify left bottom))
    )
    (fp_rect (start -0.925 -0.47) (end 0.925 0.47)
      (stroke (width 0.05) (type default)) (fill none) (layer "F.CrtYd"))
    (fp_rect (start -0.5 -0.25) (end 0.5 0.25)
      (stroke (width 0.15) (type solid)) (fill none) (layer "F.Fab"))
    (pad "1" smd roundrect (at -0.48 0 270) (size 0.59 0.64) (layers "F.Cu" "F.Paste" "F.Mask") (roundrect_rratio 0.25)
      (net 1 "VCC3V3") (pintype "passive"))
    (pad "2" smd roundrect (at 0.48 0 270) (size 0.59 0.64) (layers "F.Cu" "F.Paste" "F.Mask") (roundrect_rratio 0.25)
      (net 26 "/Power Cycling & Current Measurement/PC_5") (pintype "passive"))
  )
	(footprint "antmicro-footprints:MOLEX_39288080" (layer "F.Cu")
    (at 179.5 74.7 90)
    (property "Author" "Antmicro")
    (property "License" "Apache-2.0")
    (property "MPN" "39-28-8080")
    (property "Manufacturer" "Molex")
    (property "Sheetfile" "d1600e-psu-breakout-board.kicad_sch")
    (property "Sheetname" "")
    (property "ki_description" "Pin Header, THT, Vertical, UL94V-2, Power, Wire-to-Board, 4.2 mm, 2 Rows, 8 Contacts, Mini-fit Jr, 5566 series")
    (property "ki_keywords" "VERTICAL, THT, HEADER, CONNECTOR, MALE, WIRE-BOARD, POWER")
    (attr through_hole)
    (fp_text reference "J6" (at -2 -2.65 90) (layer "F.SilkS")
        (effects (font (size 0.7 0.7) (thickness 0.15)) (justify left bottom))
    )
    (fp_text value "Molex_Mini-Fit-Jr_2x4_39-28-8080" (at 4.49 11.365 90) (layer "F.Fab")
        (effects (font (size 0.7 0.7) (thickness 0.15)) (justify left bottom))
    )
    (fp_text user "License: Apache-2.0" (at -3.5 14.565 90) (layer "F.Fab") hide
        (effects (font (size 0.7 0.7) (thickness 0.15)) (justify left bottom))
    )
    (fp_text user "Author: Antmicro" (at -3.5 16.965 90) (layer "F.Fab") hide
        (effects (font (size 0.7 0.7) (thickness 0.15)) (justify left bottom))
    )
    (fp_text user "PTH D1.40 +/- 0.05" (at -3.5 13.365 90) (layer "F.Fab") hide
        (effects (font (size 0.7 0.7) (thickness 0.15)) (justify left bottom))
    )
    (fp_text user "${REFERENCE}" (at -3.5 15.765 90) (layer "F.Fab") hide
        (effects (font (size 0.7 0.7) (thickness 0.15)) (justify left bottom))
    )
    (fp_line (start -3.1 8.75) (end -3.1 -0.98)
      (stroke (width 0.15) (type solid)) (layer "F.SilkS"))
    (fp_line (start -1.83 -2.25) (end -3.1 -0.98)
      (stroke (width 0.15) (type solid)) (layer "F.SilkS"))
    (fp_line (start -1.83 -2.25) (end 15.7 -2.25)
      (stroke (width 0.15) (type solid)) (layer "F.SilkS"))
    (fp_line (start -0.4 -3.327) (end 0 -2.627)
      (stroke (width 0.15) (type solid)) (layer "F.SilkS"))
    (fp_line (start 0 -2.627) (end 0.4 -3.327)
      (stroke (width 0.15) (type solid)) (layer "F.SilkS"))
    (fp_line (start 0.4 -3.327) (end -0.4 -3.327)
      (stroke (width 0.15) (type solid)) (layer "F.SilkS"))
    (fp_line (start 15.7 -2.25) (end 15.7 8.75)
      (stroke (width 0.15) (type solid)) (layer "F.SilkS"))
    (fp_line (start 15.7 8.75) (end -3.1 8.75)
      (stroke (width 0.15) (type solid)) (layer "F.SilkS"))
    (fp_circle (center 0 -3) (end 0.05 -3)
      (stroke (width 0.15) (type solid)) (fill solid) (layer "F.SilkS"))
    (fp_circle (center 0 5.5) (end 0.513 5.5)
      (stroke (width 1.0262) (type solid)) (fill none) (layer "B.Mask"))
    (fp_circle (center 4.2 0) (end 4.713 0)
      (stroke (width 1.0262) (type solid)) (fill none) (layer "B.Mask"))
    (fp_circle (center 4.2 5.5) (end 4.713 5.5)
      (stroke (width 1.0262) (type solid)) (fill none) (layer "B.Mask"))
    (fp_circle (center 8.4 0) (end 8.913 0)
      (stroke (width 1.0262) (type solid)) (fill none) (layer "B.Mask"))
    (fp_circle (center 8.4 5.5) (end 8.913 5.5)
      (stroke (width 1.0262) (type solid)) (fill none) (layer "B.Mask"))
    (fp_circle (center 12.6 0) (end 13.113 0)
      (stroke (width 1.0262) (type solid)) (fill none) (layer "B.Mask"))
    (fp_circle (center 12.6 5.5) (end 13.113 5.5)
      (stroke (width 1.0262) (type solid)) (fill none) (layer "B.Mask"))
    (fp_poly
      (pts
        (xy -1.026 -1.026)
        (xy 1.026 -1.026)
        (xy 1.026 1.026)
        (xy -1.026 1.026)
      )

      (stroke (width 0.01) (type solid)) (fill solid) (layer "B.Mask"))
    (fp_circle (center 0 5.5) (end 0.513 5.5)
      (stroke (width 1.0262) (type solid)) (fill none) (layer "F.Mask"))
    (fp_circle (center 4.2 0) (end 4.713 0)
      (stroke (width 1.0262) (type solid)) (fill none) (layer "F.Mask"))
    (fp_circle (center 4.2 5.5) (end 4.713 5.5)
      (stroke (width 1.0262) (type solid)) (fill none) (layer "F.Mask"))
    (fp_circle (center 8.4 0) (end 8.913 0)
      (stroke (width 1.0262) (type solid)) (fill none) (layer "F.Mask"))
    (fp_circle (center 8.4 5.5) (end 8.913 5.5)
      (stroke (width 1.0262) (type solid)) (fill none) (layer "F.Mask"))
    (fp_circle (center 12.6 0) (end 13.113 0)
      (stroke (width 1.0262) (type solid)) (fill none) (layer "F.Mask"))
    (fp_circle (center 12.6 5.5) (end 13.113 5.5)
      (stroke (width 1.0262) (type solid)) (fill none) (layer "F.Mask"))
    (fp_poly
      (pts
        (xy -1.026 -1.026)
        (xy 1.026 -1.026)
        (xy 1.026 1.026)
        (xy -1.026 1.026)
      )

      (stroke (width 0.01) (type solid)) (fill solid) (layer "F.Mask"))
    (fp_rect (start -3.5 -2.7) (end 16.1 9.1)
      (stroke (width 0.05) (type solid)) (fill none) (layer "F.CrtYd"))
    (fp_line (start -3.1 8.75) (end -3.1 -0.98)
      (stroke (width 0.15) (type solid)) (layer "F.Fab"))
    (fp_line (start -1.83 -2.25) (end -3.1 -0.98)
      (stroke (width 0.15) (type solid)) (layer "F.Fab"))
    (fp_line (start -1.83 -2.25) (end 15.7 -2.25)
      (stroke (width 0.15) (type solid)) (layer "F.Fab"))
    (fp_line (start -0.4 -3.327) (end 0 -2.627)
      (stroke (width 0.15) (type solid)) (layer "F.Fab"))
    (fp_line (start 0 -2.627) (end 0.4 -3.327)
      (stroke (width 0.15) (type solid)) (layer "F.Fab"))
    (fp_line (start 0.4 -3.327) (end -0.4 -3.327)
      (stroke (width 0.15) (type solid)) (layer "F.Fab"))
    (fp_line (start 15.7 -2.25) (end 15.7 8.75)
      (stroke (width 0.15) (type solid)) (layer "F.Fab"))
    (fp_line (start 15.7 8.75) (end -3.1 8.75)
      (stroke (width 0.15) (type solid)) (layer "F.Fab"))
    (pad "1" thru_hole rect (at 0 0 90) (size 1.9 1.9) (drill 1.4) (layers "*.Cu")
      (net 4 "GND") (pinfunction "1") (pintype "bidirectional"))
    (pad "2" thru_hole circle (at 4.2 0 90) (size 1.9 1.9) (drill 1.4) (layers "*.Cu")
      (net 4 "GND") (pinfunction "2") (pintype "bidirectional"))
    (pad "3" thru_hole circle (at 8.4 0 90) (size 1.9 1.9) (drill 1.4) (layers "*.Cu")
      (net 4 "GND") (pinfunction "3") (pintype "bidirectional"))
    (pad "4" thru_hole circle (at 12.6 0 90) (size 1.9 1.9) (drill 1.4) (layers "*.Cu")
      (net 4 "GND") (pinfunction "4") (pintype "bidirectional"))
    (pad "5" thru_hole circle (at 0 5.5 90) (size 1.9 1.9) (drill 1.4) (layers "*.Cu")
      (net 43 "LOAD_5") (pinfunction "5") (pintype "bidirectional"))
    (pad "6" thru_hole circle (at 4.2 5.5 90) (size 1.9 1.9) (drill 1.4) (layers "*.Cu")
      (net 43 "LOAD_5") (pinfunction "6") (pintype "bidirectional"))
    (pad "7" thru_hole circle (at 8.4 5.5 90) (size 1.9 1.9) (drill 1.4) (layers "*.Cu")
      (net 43 "LOAD_5") (pinfunction "7") (pintype "bidirectional"))
    (pad "8" thru_hole circle (at 12.6 5.5 90) (size 1.9 1.9) (drill 1.4) (layers "*.Cu")
      (net 43 "LOAD_5") (pinfunction "8") (pintype "bidirectional"))
  )
	(footprint "antmicro-footprints:R_0402_1005Metric" (layer "F.Cu")
    (at 181.215 93.6)
    (descr "Resistor SMD 0402")
    (tags "resistor SMD 0402")
    (property "Author" "Antmicro")
    (property "Current" "1A")
    (property "DNP" "DNP")
    (property "License" "Apache-2.0")
    (property "MPN" "ERJ2GE0R00X")
    (property "Manufacturer" "Panasonic")
    (property "Sheetfile" "d1600e-psu-breakout-board.kicad_sch")
    (property "Sheetname" "")
    (property "Tolerance" "")
    (property "Val" "0R")
    (property "dnp" "")
    (property "exclude_from_bom" "")
    (property "ki_description" "SMD Chip Resistor, Jumper, 0 ohm, 100 mW, 0402 [1005 Metric], Thick Film, General Purpose")
    (property "ki_keywords" "0402, SMT, RESISTOR, PASSIVE")
    (attr smd exclude_from_bom)
    (fp_text reference "R9" (at -1.365 0.85) (layer "F.SilkS")
        (effects (font (size 0.7 0.7) (thickness 0.15)))
    )
    (fp_text value "R_0R_0402" (at 0 1.17) (layer "F.Fab") hide
        (effects (font (size 1 1) (thickness 0.15)))
    )
    (fp_text user "Author: Antmicro" (at -0.95 4.169) (layer "F.Fab") hide
        (effects (font (size 0.7 0.7) (thickness 0.15)) (justify left bottom))
    )
    (fp_text user "${REFERENCE}" (at 0 0) (layer "F.Fab")
        (effects (font (size 0.7 0.7) (thickness 0.15)))
    )
    (fp_text user "License: Apache-2.0" (at -0.95 5.169) (layer "F.Fab") hide
        (effects (font (size 0.7 0.7) (thickness 0.15)) (justify left bottom))
    )
    (fp_rect (start -0.925 -0.47) (end 0.925 0.47)
      (stroke (width 0.05) (type default)) (fill none) (layer "F.CrtYd"))
    (fp_rect (start -0.5 -0.25) (end 0.5 0.25)
      (stroke (width 0.15) (type solid)) (fill none) (layer "F.Fab"))
    (pad "1" smd roundrect (at -0.48 0) (size 0.59 0.64) (layers "F.Cu" "F.Paste" "F.Mask") (roundrect_rratio 0.25)
      (net 1 "VCC3V3") (pintype "passive"))
    (pad "2" smd roundrect (at 0.48 0) (size 0.59 0.64) (layers "F.Cu" "F.Paste" "F.Mask") (roundrect_rratio 0.25)
      (net 19 "Net-(J2-Pad1)") (pintype "passive"))
  )
	(footprint "antmicro-footprints:SOIC-8_3.9x4.9x1.75mm_P1.27mm" (layer "F.Cu")
    (at 179.75 82.1508 180)
    (property "Author" "Antmicro")
    (property "License" "Apache-2.0")
    (property "MPN" "TMCS1100A2QDRQ1")
    (property "Manufacturer" "Texas Instruments")
    (property "Sheetfile" "pow-cycl-curr-meas.kicad_sch")
    (property "Sheetname" "Power Cycling & Current Measurement")
    (property "ki_description" "Hall current Sensor/transducer")
    (property "ki_keywords" "SMT, SENSOR, IC, POWER")
    (attr smd)
    (fp_text reference "U13" (at 1.2 2.8508) (layer "F.SilkS")
        (effects (font (size 0.7 0.7) (thickness 0.15)) (justify right bottom))
    )
    (fp_text value "TMCS1100A2-Q1" (at 0 3.65) (layer "F.Fab")
        (effects (font (size 0.7 0.7) (thickness 0.15)) (justify right bottom))
    )
    (fp_text user "License: Apache-2.0" (at -3.476 5.099) (layer "F.Fab") hide
        (effects (font (size 0.7 0.7) (thickness 0.15)) (justify right bottom))
    )
    (fp_text user "${REFERENCE}" (at -3.476 7.099) (layer "F.Fab") hide
        (effects (font (size 0.7 0.7) (thickness 0.15)) (justify right bottom))
    )
    (fp_text user "Author: Antmicro" (at -3.476 6.099) (layer "F.Fab") hide
        (effects (font (size 0.7 0.7) (thickness 0.15)) (justify right bottom))
    )
    (fp_line (start -1.95 -2.452) (end 1.95 -2.45)
      (stroke (width 0.15) (type solid)) (layer "F.SilkS"))
    (fp_line (start -1.95 2.45) (end 1.95 2.45)
      (stroke (width 0.15) (type solid)) (layer "F.SilkS"))
    (fp_circle (center -2.4 -2.45) (end -2.35 -2.4)
      (stroke (width 0.15) (type solid)) (fill solid) (layer "F.SilkS"))
    (fp_rect (start -3.625 -2.7) (end 3.625 2.7)
      (stroke (width 0.05) (type solid)) (fill none) (layer "F.CrtYd"))
    (fp_line (start -1.95 -1.18) (end -0.683 -2.452)
      (stroke (width 0.15) (type solid)) (layer "F.Fab"))
    (fp_line (start -1.95 2.45) (end -1.95 -1.18)
      (stroke (width 0.15) (type solid)) (layer "F.Fab"))
    (fp_line (start -0.683 -2.452) (end 1.949 -2.452)
      (stroke (width 0.15) (type solid)) (layer "F.Fab"))
    (fp_line (start 1.949 -2.452) (end 1.949 2.45)
      (stroke (width 0.15) (type solid)) (layer "F.Fab"))
    (fp_line (start 1.949 2.45) (end -1.95 2.45)
      (stroke (width 0.15) (type solid)) (layer "F.Fab"))
    (pad "1" smd roundrect (at -2.714 -1.905 270) (size 0.65 1.525) (layers "F.Cu" "F.Paste" "F.Mask") (roundrect_rratio 0.25)
      (net 25 "C_MEAS_5") (pinfunction "IN+") (pintype "input"))
    (pad "2" smd roundrect (at -2.714 -0.635 270) (size 0.65 1.525) (layers "F.Cu" "F.Paste" "F.Mask") (roundrect_rratio 0.25)
      (net 25 "C_MEAS_5") (pinfunction "IN+") (pintype "input"))
    (pad "3" smd roundrect (at -2.714 0.632 270) (size 0.65 1.525) (layers "F.Cu" "F.Paste" "F.Mask") (roundrect_rratio 0.25)
      (net 43 "LOAD_5") (pinfunction "IN-") (pintype "input"))
    (pad "4" smd roundrect (at -2.714 1.902 270) (size 0.65 1.525) (layers "F.Cu" "F.Paste" "F.Mask") (roundrect_rratio 0.25)
      (net 43 "LOAD_5") (pinfunction "IN-") (pintype "input"))
    (pad "5" smd roundrect (at 2.712 1.902 270) (size 0.65 1.525) (layers "F.Cu" "F.Paste" "F.Mask") (roundrect_rratio 0.25)
      (net 4 "GND") (pinfunction "GND") (pintype "power_in"))
    (pad "6" smd roundrect (at 2.712 0.632 270) (size 0.65 1.525) (layers "F.Cu" "F.Paste" "F.Mask") (roundrect_rratio 0.25)
      (net 4 "GND") (pinfunction "VREF") (pintype "input"))
    (pad "7" smd roundrect (at 2.712 -0.635 270) (size 0.65 1.525) (layers "F.Cu" "F.Paste" "F.Mask") (roundrect_rratio 0.25)
      (net 50 "/Power Cycling & Current Measurement/C_ADC5") (pinfunction "VOUT") (pintype "output"))
    (pad "8" smd roundrect (at 2.712 -1.905 270) (size 0.65 1.525) (layers "F.Cu" "F.Paste" "F.Mask") (roundrect_rratio 0.25)
      (net 1 "VCC3V3") (pinfunction "VCC") (pintype "power_in"))
  )
	(footprint "antmicro-footprints:R_0402_1005Metric" (layer "F.Cu")
    (at 143.5 87)
    (descr "Resistor SMD 0402")
    (tags "resistor SMD 0402")
    (property "Author" "Antmicro")
    (property "License" "Apache-2.0")
    (property "MPN" "CR0402-FX-1002GLF")
    (property "Manufacturer" "Bourns")
    (property "Sheetfile" "power-switch.kicad_sch")
    (property "Sheetname" "Power switch 3")
    (property "Tolerance" "1%")
    (property "Val" "10k")
    (property "ki_description" "SMD Chip Resistor, 10 kohm, ± 1%, 62.5 mW, 0402 [1005 Metric], Thick Film, General Purpose")
    (property "ki_keywords" "0402, SMT, RESISTOR, PASSIVE")
    (attr smd)
    (fp_text reference "R27" (at -2 0.1 180) (layer "F.SilkS")
        (effects (font (size 0.7 0.7) (thickness 0.15)))
    )
    (fp_text value "R_10k_0402" (at 0 1.17) (layer "F.Fab") hide
        (effects (font (size 1 1) (thickness 0.15)))
    )
    (fp_text user "Author: Antmicro" (at -0.95 4.169) (layer "F.Fab") hide
        (effects (font (size 0.7 0.7) (thickness 0.15)) (justify left bottom))
    )
    (fp_text user "${REFERENCE}" (at 0 0) (layer "F.Fab")
        (effects (font (size 0.7 0.7) (thickness 0.15)))
    )
    (fp_text user "License: Apache-2.0" (at -0.95 5.169) (layer "F.Fab") hide
        (effects (font (size 0.7 0.7) (thickness 0.15)) (justify left bottom))
    )
    (fp_rect (start -0.925 -0.47) (end 0.925 0.47)
      (stroke (width 0.05) (type default)) (fill none) (layer "F.CrtYd"))
    (fp_rect (start -0.5 -0.25) (end 0.5 0.25)
      (stroke (width 0.15) (type solid)) (fill none) (layer "F.Fab"))
    (pad "1" smd roundrect (at -0.48 0) (size 0.59 0.64) (layers "F.Cu" "F.Paste" "F.Mask") (roundrect_rratio 0.25)
      (net 1 "VCC3V3") (pintype "passive"))
    (pad "2" smd roundrect (at 0.48 0) (size 0.59 0.64) (layers "F.Cu" "F.Paste" "F.Mask") (roundrect_rratio 0.25)
      (net 30 "/Power Cycling & Current Measurement/PC_3") (pintype "passive"))
  )
	(footprint "antmicro-footprints:R_0402_1005Metric" (layer "F.Cu")
    (at 166.85 96.5 -90)
    (descr "Resistor SMD 0402")
    (tags "resistor SMD 0402")
    (property "Author" "Antmicro")
    (property "Current" "1A")
    (property "License" "Apache-2.0")
    (property "MPN" "ERJ2GE0R00X")
    (property "Manufacturer" "Panasonic")
    (property "Sheetfile" "pow-cycl-curr-meas.kicad_sch")
    (property "Sheetname" "Power Cycling & Current Measurement")
    (property "Tolerance" "")
    (property "Val" "0R")
    (property "ki_description" "SMD Chip Resistor, Jumper, 0 ohm, 100 mW, 0402 [1005 Metric], Thick Film, General Purpose")
    (property "ki_keywords" "0402, SMT, RESISTOR, PASSIVE")
    (attr smd)
    (fp_text reference "R14" (at -0.85 -0.4 -90) (layer "F.SilkS")
        (effects (font (size 0.7 0.7) (thickness 0.15)) (justify left bottom))
    )
    (fp_text value "R_0R_0402" (at -1.011843 1.772047 -90) (layer "F.Fab")
        (effects (font (size 0.7 0.7) (thickness 0.15)) (justify left bottom))
    )
    (fp_text user "Author: Antmicro" (at -0.95 4.169 -90) (layer "F.Fab") hide
        (effects (font (size 0.7 0.7) (thickness 0.15)) (justify left bottom))
    )
    (fp_text user "${REFERENCE}" (at -0.95 3.168 -90) (layer "F.Fab") hide
        (effects (font (size 0.7 0.7) (thickness 0.15)) (justify left bottom))
    )
    (fp_text user "License: Apache-2.0" (at -0.95 5.169 -90) (layer "F.Fab") hide
        (effects (font (size 0.7 0.7) (thickness 0.15)) (justify left bottom))
    )
    (fp_rect (start -0.925 -0.47) (end 0.925 0.47)
      (stroke (width 0.05) (type default)) (fill none) (layer "F.CrtYd"))
    (fp_rect (start -0.5 -0.25) (end 0.5 0.25)
      (stroke (width 0.15) (type solid)) (fill none) (layer "F.Fab"))
    (pad "1" smd roundrect (at -0.48 0 270) (size 0.59 0.64) (layers "F.Cu" "F.Paste" "F.Mask") (roundrect_rratio 0.25)
      (net 105 "Net-(U10-A0)") (pintype "passive"))
    (pad "2" smd roundrect (at 0.48 0 270) (size 0.59 0.64) (layers "F.Cu" "F.Paste" "F.Mask") (roundrect_rratio 0.25)
      (net 4 "GND") (pintype "passive"))
  )
)
